(kicad_pcb
	(version 20260206)
	(generator "pcbnew")
	(generator_version "10.0")
	(general
		(thickness 1.6)
		(legacy_teardrops no)
	)
	(paper "A4")
	(title_block
		(title "Bryce Canyon_R.DPB_16317-1_OCP.brd")
		(comment 1 "Bryce Canyon / footprints 283-289 of 2099")
	)
	(layers
		(0 "F.Cu" signal "TOP")
		(4 "In1.Cu" signal "L2GND")
		(6 "In2.Cu" signal "L3")
		(8 "In3.Cu" signal "L4VCC")
		(10 "In4.Cu" signal "L5VCC")
		(12 "In5.Cu" signal "L6")
		(14 "In6.Cu" signal "L7GND")
		(2 "B.Cu" signal "BOTTOM")
		(9 "F.Adhes" user "F.Adhesive")
		(11 "B.Adhes" user "B.Adhesive")
		(13 "F.Paste" user "Package Geometry/Pastemask Top")
		(15 "B.Paste" user "Package Geometry/Pastemask Bottom")
		(5 "F.SilkS" user "Ref Des/Silkscreen Top")
		(7 "B.SilkS" user "Ref Des/Silkscreen Bottom")
		(1 "F.Mask" user "Board Geometry/Soldermask Top")
		(3 "B.Mask" user "Board Geometry/Soldermask Bottom")
		(17 "Dwgs.User" user "User.Drawings")
		(19 "Cmts.User" user "User.Comments")
		(21 "Eco1.User" user "User.Eco1")
		(23 "Eco2.User" user "User.Eco2")
		(25 "Edge.Cuts" user "Board Geometry/Outline")
		(27 "Margin" user)
		(31 "F.CrtYd" user "Package Geometry/Place Bound Top")
		(29 "B.CrtYd" user "Package Geometry/Place Bound Bottom")
		(35 "F.Fab" user "Ref Des/Assembly Top")
		(33 "B.Fab" user "Ref Des/Assembly Bottom")
	)
	(footprint ""
		(layer "F.Cu")
		(at 174.498 -139.065 -90)
		(property "Reference" "C259"
			(at 0 0 270)
			(layer "F.SilkS")
			(hide yes)
			(effects
				(font
					(size 1.27 1.27)
				)
			)
		)
		(property "Value" "SCD033U25V2KX-GP"
			(at 1.1811 -2.7051 270)
			(unlocked yes)
			(layer "F.Fab")
			(hide yes)
			(effects
				(font
					(size 1.016 1.016)
					(thickness 0.1524)
				)
			)
		)
		(property "Device Type" "C402H22"
			(at 1.1811 -4.2291 270)
			(unlocked yes)
			(layer "F.Fab")
			(hide yes)
			(effects
				(font
					(size 1.016 1.016)
					(thickness 0.1524)
				)
			)
		)
		(duplicate_pad_numbers_are_jumpers no)
		(fp_rect
			(start -0.4318 0.9525)
			(end 0.4318 -0.9525)
			(stroke
				(width 0)
				(type default)
			)
			(fill no)
			(layer "F.CrtYd")
		)
		(fp_rect
			(start -0.4318 0.9525)
			(end 0.4318 -0.9525)
			(stroke
				(width 0)
				(type default)
			)
			(fill no)
			(layer "F.Fab")
		)
		(pad "1" smd custom
			(at 0 -0.4445 270)
			(size 0.1524 0.1524)
			(layers "F.Cu" "F.Mask" "F.Paste")
			(net "SW_HDD_P17")
			(options
				(clearance outline)
				(anchor circle)
			)
			(primitives
				(gr_poly
					(pts
						(arc
							(start 0.3048 -0.2032)
							(mid 0.275042 -0.275042)
							(end 0.2032 -0.3048)
						)
						(arc
							(start -0.2032 -0.3048)
							(mid -0.275042 -0.275042)
							(end -0.3048 -0.2032)
						)
						(arc
							(start -0.3048 0.2032)
							(mid -0.275042 0.275042)
							(end -0.2032 0.3048)
						)
						(arc
							(start 0.2032 0.3048)
							(mid 0.275042 0.275042)
							(end 0.3048 0.2032)
						)
					)
					(width 0)
					(fill yes)
				)
			)
		)
		(pad "2" smd custom
			(at 0 0.4445 270)
			(size 0.1524 0.1524)
			(layers "F.Cu" "F.Mask" "F.Paste")
			(net "GND")
			(options
				(clearance outline)
				(anchor circle)
			)
			(primitives
				(gr_poly
					(pts
						(arc
							(start 0.3048 -0.2032)
							(mid 0.275042 -0.275042)
							(end 0.2032 -0.3048)
						)
						(arc
							(start -0.2032 -0.3048)
							(mid -0.275042 -0.275042)
							(end -0.3048 -0.2032)
						)
						(arc
							(start -0.3048 0.2032)
							(mid -0.275042 0.275042)
							(end -0.2032 0.3048)
						)
						(arc
							(start 0.2032 0.3048)
							(mid 0.275042 0.275042)
							(end 0.3048 0.2032)
						)
					)
					(width 0)
					(fill yes)
				)
			)
		)
	)
	(footprint ""
		(layer "F.Cu")
		(at 257.458972 -372.32971 180)
		(property "Reference" "R1040"
			(at 0 0 180)
			(layer "F.SilkS")
			(hide yes)
			(effects
				(font
					(size 1.27 1.27)
				)
			)
		)
		(property "Value" "3K83R2F-GP"
			(at 0.064008 -3.993896 180)
			(unlocked yes)
			(layer "F.Fab")
			(hide yes)
			(effects
				(font
					(size 1.016 1.016)
					(thickness 0.1524)
				)
			)
		)
		(property "Device Type" "R402H16"
			(at 0.064008 -5.517896 180)
			(unlocked yes)
			(layer "F.Fab")
			(hide yes)
			(effects
				(font
					(size 1.016 1.016)
					(thickness 0.1524)
				)
			)
		)
		(duplicate_pad_numbers_are_jumpers no)
		(fp_line
			(start 0.508 -0.9398)
			(end -0.508 -0.9398)
			(stroke
				(width 0.1524)
				(type default)
			)
			(layer "F.SilkS")
		)
		(fp_line
			(start -0.508 -0.9398)
			(end -0.508 0.9398)
			(stroke
				(width 0.1524)
				(type default)
			)
			(layer "F.SilkS")
		)
		(fp_rect
			(start -0.508 0.9398)
			(end 0.508 -0.9398)
			(stroke
				(width 0)
				(type default)
			)
			(fill no)
			(layer "F.CrtYd")
		)
		(fp_rect
			(start -0.508 0.9398)
			(end 0.508 -0.9398)
			(stroke
				(width 0)
				(type default)
			)
			(fill no)
			(layer "F.Fab")
		)
		(pad "1" smd custom
			(at 0 -0.4445 180)
			(size 0.1397 0.1397)
			(layers "F.Cu" "F.Mask" "F.Paste")
			(net "P12V_B_PGOOD")
			(options
				(clearance outline)
				(anchor circle)
			)
			(primitives
				(gr_poly
					(pts
						(arc
							(start -0.1778 -0.2794)
							(mid -0.249642 -0.249642)
							(end -0.2794 -0.1778)
						)
						(arc
							(start -0.2794 0.1778)
							(mid -0.249642 0.249642)
							(end -0.1778 0.2794)
						)
						(arc
							(start 0.1778 0.2794)
							(mid 0.249642 0.249642)
							(end 0.2794 0.1778)
						)
						(arc
							(start 0.2794 -0.1778)
							(mid 0.249642 -0.249642)
							(end 0.1778 -0.2794)
						)
					)
					(width 0)
					(fill yes)
				)
			)
		)
		(pad "2" smd custom
			(at 0 0.4445 180)
			(size 0.1397 0.1397)
			(layers "F.Cu" "F.Mask" "F.Paste")
			(net "GND")
			(options
				(clearance outline)
				(anchor circle)
			)
			(primitives
				(gr_poly
					(pts
						(arc
							(start -0.1778 -0.2794)
							(mid -0.249642 -0.249642)
							(end -0.2794 -0.1778)
						)
						(arc
							(start -0.2794 0.1778)
							(mid -0.249642 0.249642)
							(end -0.1778 0.2794)
						)
						(arc
							(start 0.1778 0.2794)
							(mid 0.249642 0.249642)
							(end 0.2794 0.1778)
						)
						(arc
							(start 0.2794 -0.1778)
							(mid 0.249642 -0.249642)
							(end 0.1778 -0.2794)
						)
					)
					(width 0)
					(fill yes)
				)
			)
		)
	)
	(footprint ""
		(layer "F.Cu")
		(at 178.435 -256.286 180)
		(property "Reference" "Q18"
			(at 0 0 180)
			(layer "F.SilkS")
			(hide yes)
			(effects
				(font
					(size 1.27 1.27)
				)
			)
		)
		(property "Value" "AO4406AL-GP"
			(at -3.707384 -1.5367 180)
			(unlocked yes)
			(layer "F.Fab")
			(hide yes)
			(effects
				(font
					(size 1.016 1.016)
					(thickness 0.1524)
				)
			)
		)
		(property "Device Type" "SOIC8H69"
			(at -3.707384 -3.0607 180)
			(unlocked yes)
			(layer "F.Fab")
			(hide yes)
			(effects
				(font
					(size 1.016 1.016)
					(thickness 0.1524)
				)
			)
		)
		(duplicate_pad_numbers_are_jumpers no)
		(fp_line
			(start 2.1336 1.4224)
			(end 2.1336 -1.4224)
			(stroke
				(width 0.1524)
				(type default)
			)
			(layer "F.SilkS")
		)
		(fp_line
			(start 2.1336 -1.4224)
			(end -2.7432 -1.4224)
			(stroke
				(width 0.1524)
				(type default)
			)
			(layer "F.SilkS")
		)
		(fp_line
			(start -2.1844 -0.0508)
			(end -2.7178 0.508)
			(stroke
				(width 0.1524)
				(type default)
			)
			(layer "F.SilkS")
		)
		(fp_line
			(start -2.6289 3.4417)
			(end -2.6289 1.4732)
			(stroke
				(width 0.381)
				(type default)
			)
			(layer "F.SilkS")
		)
		(fp_line
			(start -2.7178 -0.508)
			(end -2.1844 -0.0508)
			(stroke
				(width 0.1524)
				(type default)
			)
			(layer "F.SilkS")
		)
		(fp_line
			(start -2.7432 1.4224)
			(end 2.1336 1.4224)
			(stroke
				(width 0.1524)
				(type default)
			)
			(layer "F.SilkS")
		)
		(fp_line
			(start -2.7432 1.4224)
			(end -2.6416 1.4224)
			(stroke
				(width 0.1524)
				(type default)
			)
			(layer "F.SilkS")
		)
		(fp_line
			(start -2.7432 -1.4224)
			(end -2.7432 1.4224)
			(stroke
				(width 0.1524)
				(type default)
			)
			(layer "F.SilkS")
		)
		(fp_poly
			(pts
				(xy -2.2098 -1.4224) (xy -2.2098 1.4224) (xy 2.2098 1.4224) (xy 2.2098 -1.4224)
			)
			(stroke
				(width 0)
				(type default)
			)
			(fill yes)
			(layer "F.SilkS")
		)
		(fp_rect
			(start -2.450084 2.999994)
			(end 2.450084 -2.999994)
			(stroke
				(width 0)
				(type default)
			)
			(fill no)
			(layer "F.CrtYd")
		)
		(fp_poly
			(pts
				(xy -2.8194 3.6322) (xy -2.8194 -3.6322) (xy 2.8194 -3.6322) (xy 2.8194 1.18364) (xy 2.450084 1.18364)
				(xy 2.450084 -2.999994) (xy -2.450084 -2.999994) (xy -2.450084 2.999994) (xy 2.450084 2.999994)
				(xy 2.450084 1.18618) (xy 2.8194 1.18618) (xy 2.8194 3.6322)
			)
			(stroke
				(width 0)
				(type default)
			)
			(fill no)
			(layer "F.CrtYd")
		)
		(fp_rect
			(start -2.8194 3.6322)
			(end 2.8194 -3.6322)
			(stroke
				(width 0)
				(type default)
			)
			(fill no)
			(layer "F.Fab")
		)
		(pad "1" smd rect
			(at -1.905 2.54 180)
			(size 0.635 1.651)
			(layers "F.Cu" "F.Mask" "F.Paste")
			(net "P5V_HDD5")
		)
		(pad "2" smd rect
			(at -0.635 2.54 180)
			(size 0.635 1.651)
			(layers "F.Cu" "F.Mask" "F.Paste")
			(net "P5V_HDD5")
		)
		(pad "3" smd rect
			(at 0.635 2.54 180)
			(size 0.635 1.651)
			(layers "F.Cu" "F.Mask" "F.Paste")
			(net "P5V_HDD5")
		)
		(pad "4" smd rect
			(at 1.905 2.54 180)
			(size 0.635 1.651)
			(layers "F.Cu" "F.Mask" "F.Paste")
			(net "SW_HDD_P5")
		)
		(pad "5" smd rect
			(at 1.905 -2.54 180)
			(size 0.635 1.651)
			(layers "F.Cu" "F.Mask" "F.Paste")
			(net "P5V_B_1")
		)
		(pad "6" smd rect
			(at 0.635 -2.54 180)
			(size 0.635 1.651)
			(layers "F.Cu" "F.Mask" "F.Paste")
			(net "P5V_B_1")
		)
		(pad "7" smd rect
			(at -0.635 -2.54 180)
			(size 0.635 1.651)
			(layers "F.Cu" "F.Mask" "F.Paste")
			(net "P5V_B_1")
		)
		(pad "8" smd rect
			(at -1.905 -2.54 180)
			(size 0.635 1.651)
			(layers "F.Cu" "F.Mask" "F.Paste")
			(net "P5V_B_1")
		)
	)
	(footprint ""
		(layer "F.Cu")
		(at 52.578 -16.637 -90)
		(property "Reference" "Q125"
			(at 0 0 270)
			(layer "F.SilkS")
			(hide yes)
			(effects
				(font
					(size 1.27 1.27)
				)
			)
		)
		(property "Value" "2N7002KDW-GP"
			(at -2.3622 -8.2042 270)
			(unlocked yes)
			(layer "F.Fab")
			(hide yes)
			(effects
				(font
					(size 1.016 1.016)
					(thickness 0.1524)
				)
			)
		)
		(property "Device Type" "SOT-363H44"
			(at -2.3622 -10.1092 270)
			(unlocked yes)
			(layer "F.Fab")
			(hide yes)
			(effects
				(font
					(size 1.016 1.016)
					(thickness 0.1524)
				)
			)
		)
		(duplicate_pad_numbers_are_jumpers no)
		(fp_line
			(start -1.4478 1.7018)
			(end 1.4478 1.7018)
			(stroke
				(width 0.1524)
				(type default)
			)
			(layer "F.SilkS")
		)
		(fp_line
			(start 1.4478 1.7018)
			(end 1.4478 -1.7018)
			(stroke
				(width 0.1524)
				(type default)
			)
			(layer "F.SilkS")
		)
		(fp_line
			(start -1.27 1.524)
			(end -1.27 0.6604)
			(stroke
				(width 0.4826)
				(type default)
			)
			(layer "F.SilkS")
		)
		(fp_line
			(start -1.4478 -1.7018)
			(end -1.4478 1.7018)
			(stroke
				(width 0.1524)
				(type default)
			)
			(layer "F.SilkS")
		)
		(fp_line
			(start 1.4478 -1.7018)
			(end -1.4478 -1.7018)
			(stroke
				(width 0.1524)
				(type default)
			)
			(layer "F.SilkS")
		)
		(fp_poly
			(pts
				(xy -1.524 -1.778) (xy 1.524 -1.778) (xy 1.524 1.778) (xy -1.524 1.778)
			)
			(stroke
				(width 0)
				(type default)
			)
			(fill no)
			(layer "F.CrtYd")
		)
		(fp_poly
			(pts
				(xy -1.524 -1.778) (xy 1.524 -1.778) (xy 1.524 1.778) (xy -1.524 1.778)
			)
			(stroke
				(width 0)
				(type default)
			)
			(fill no)
			(layer "F.Fab")
		)
		(pad "1" smd rect
			(at -0.65024 0.9398 270)
			(size 0.4064 1.016)
			(layers "F.Cu" "F.Mask" "F.Paste")
			(net "GND")
		)
		(pad "2" smd rect
			(at 0 0.9398 270)
			(size 0.4064 1.016)
			(layers "F.Cu" "F.Mask" "F.Paste")
			(net "SW_PWR_R_HDD25")
		)
		(pad "3" smd rect
			(at 0.65024 0.9398 270)
			(size 0.4064 1.016)
			(layers "F.Cu" "F.Mask" "F.Paste")
			(net "SW_HDD_P25")
		)
		(pad "4" smd rect
			(at 0.65024 -0.9398 270)
			(size 0.4064 1.016)
			(layers "F.Cu" "F.Mask" "F.Paste")
			(net "GND")
		)
		(pad "5" smd rect
			(at 0 -0.9398 270)
			(size 0.4064 1.016)
			(layers "F.Cu" "F.Mask" "F.Paste")
			(net "SW_HDD_G25")
		)
		(pad "6" smd rect
			(at -0.65024 -0.9398 270)
			(size 0.4064 1.016)
			(layers "F.Cu" "F.Mask" "F.Paste")
			(net "SW_HDD_R25")
		)
	)
	(footprint ""
		(layer "F.Cu")
		(at 55.4228 -99.314)
		(property "Reference" "R397"
			(at 0 0 0)
			(layer "F.SilkS")
			(hide yes)
			(effects
				(font
					(size 1.27 1.27)
				)
			)
		)
		(property "Value" "91R3F-1-GP"
			(at -0.0254 -2.5146 0)
			(unlocked yes)
			(layer "F.Fab")
			(hide yes)
			(effects
				(font
					(size 1.016 1.016)
					(thickness 0.1524)
				)
			)
		)
		(property "Device Type" "R603H22"
			(at -0.0254 -4.0386 0)
			(unlocked yes)
			(layer "F.Fab")
			(hide yes)
			(effects
				(font
					(size 1.016 1.016)
					(thickness 0.1524)
				)
			)
		)
		(duplicate_pad_numbers_are_jumpers no)
		(fp_line
			(start -0.4826 0)
			(end -0.2032 0)
			(stroke
				(width 0.2032)
				(type default)
			)
			(layer "F.SilkS")
		)
		(fp_line
			(start 0.2032 0)
			(end 0.4826 0)
			(stroke
				(width 0.2032)
				(type default)
			)
			(layer "F.SilkS")
		)
		(fp_rect
			(start -0.5842 1.3335)
			(end 0.5842 -1.3335)
			(stroke
				(width 0)
				(type default)
			)
			(fill no)
			(layer "F.CrtYd")
		)
		(fp_rect
			(start -0.5842 1.3335)
			(end 0.5842 -1.3335)
			(stroke
				(width 0)
				(type default)
			)
			(fill no)
			(layer "F.Fab")
		)
		(pad "1" smd custom
			(at 0 -0.762)
			(size 0.2159 0.2159)
			(layers "F.Cu" "F.Mask" "F.Paste")
			(net "P5V_B_1")
			(options
				(clearance outline)
				(anchor circle)
			)
			(primitives
				(gr_poly
					(pts
						(arc
							(start -0.3302 -0.4318)
							(mid -0.402042 -0.402042)
							(end -0.4318 -0.3302)
						)
						(arc
							(start -0.4318 0.3302)
							(mid -0.402042 0.402042)
							(end -0.3302 0.4318)
						)
						(arc
							(start 0.3302 0.4318)
							(mid 0.402042 0.402042)
							(end 0.4318 0.3302)
						)
						(arc
							(start 0.4318 -0.3302)
							(mid 0.402042 -0.402042)
							(end 0.3302 -0.4318)
						)
					)
					(width 0)
					(fill yes)
				)
			)
		)
		(pad "2" smd custom
			(at 0 0.762)
			(size 0.2159 0.2159)
			(layers "F.Cu" "F.Mask" "F.Paste")
			(net "DRV_ACT_13")
			(options
				(clearance outline)
				(anchor circle)
			)
			(primitives
				(gr_poly
					(pts
						(arc
							(start -0.3302 -0.4318)
							(mid -0.402042 -0.402042)
							(end -0.4318 -0.3302)
						)
						(arc
							(start -0.4318 0.3302)
							(mid -0.402042 0.402042)
							(end -0.3302 0.4318)
						)
						(arc
							(start 0.3302 0.4318)
							(mid 0.402042 0.402042)
							(end 0.4318 0.3302)
						)
						(arc
							(start 0.4318 -0.3302)
							(mid 0.402042 -0.402042)
							(end 0.3302 -0.4318)
						)
					)
					(width 0)
					(fill yes)
				)
			)
		)
	)
	(footprint ""
		(layer "F.Cu")
		(at 430.403 -16.764 180)
		(property "Reference" "R846"
			(at 0 0 180)
			(layer "F.SilkS")
			(hide yes)
			(effects
				(font
					(size 1.27 1.27)
				)
			)
		)
		(property "Value" "0R2J-2-GP"
			(at 0.064008 -3.993896 180)
			(unlocked yes)
			(layer "F.Fab")
			(hide yes)
			(effects
				(font
					(size 1.016 1.016)
					(thickness 0.1524)
				)
			)
		)
		(property "Device Type" "R402H16"
			(at 0.064008 -5.517896 180)
			(unlocked yes)
			(layer "F.Fab")
			(hide yes)
			(effects
				(font
					(size 1.016 1.016)
					(thickness 0.1524)
				)
			)
		)
		(duplicate_pad_numbers_are_jumpers no)
		(fp_line
			(start 0.508 -0.9398)
			(end -0.508 -0.9398)
			(stroke
				(width 0.1524)
				(type default)
			)
			(layer "F.SilkS")
		)
		(fp_line
			(start -0.508 -0.9398)
			(end -0.508 0.9398)
			(stroke
				(width 0.1524)
				(type default)
			)
			(layer "F.SilkS")
		)
		(fp_rect
			(start -0.508 0.9398)
			(end 0.508 -0.9398)
			(stroke
				(width 0)
				(type default)
			)
			(fill no)
			(layer "F.CrtYd")
		)
		(fp_rect
			(start -0.508 0.9398)
			(end 0.508 -0.9398)
			(stroke
				(width 0)
				(type default)
			)
			(fill no)
			(layer "F.Fab")
		)
		(pad "1" smd custom
			(at 0 -0.4445 180)
			(size 0.1397 0.1397)
			(layers "F.Cu" "F.Mask" "F.Paste")
			(net "SW_HDD_G33")
			(options
				(clearance outline)
				(anchor circle)
			)
			(primitives
				(gr_poly
					(pts
						(arc
							(start -0.1778 -0.2794)
							(mid -0.249642 -0.249642)
							(end -0.2794 -0.1778)
						)
						(arc
							(start -0.2794 0.1778)
							(mid -0.249642 0.249642)
							(end -0.1778 0.2794)
						)
						(arc
							(start 0.1778 0.2794)
							(mid 0.249642 0.249642)
							(end 0.2794 0.1778)
						)
						(arc
							(start 0.2794 -0.1778)
							(mid 0.249642 -0.249642)
							(end 0.1778 -0.2794)
						)
					)
					(width 0)
					(fill yes)
				)
			)
		)
		(pad "2" smd custom
			(at 0 0.4445 180)
			(size 0.1397 0.1397)
			(layers "F.Cu" "F.Mask" "F.Paste")
			(net "SW_HDD_R33")
			(options
				(clearance outline)
				(anchor circle)
			)
			(primitives
				(gr_poly
					(pts
						(arc
							(start -0.1778 -0.2794)
							(mid -0.249642 -0.249642)
							(end -0.2794 -0.1778)
						)
						(arc
							(start -0.2794 0.1778)
							(mid -0.249642 0.249642)
							(end -0.1778 0.2794)
						)
						(arc
							(start 0.1778 0.2794)
							(mid 0.249642 0.249642)
							(end 0.2794 0.1778)
						)
						(arc
							(start 0.2794 -0.1778)
							(mid 0.249642 -0.249642)
							(end 0.1778 -0.2794)
						)
					)
					(width 0)
					(fill yes)
				)
			)
		)
	)
	(footprint ""
		(layer "F.Cu")
		(at 114.681 -146.939 -90)
		(property "Reference" "C226"
			(at 0 0 270)
			(layer "F.SilkS")
			(hide yes)
			(effects
				(font
					(size 1.27 1.27)
				)
			)
		)
		(property "Value" "SC10U16V6KX-2GP"
			(at -0.0762 -5.1308 270)
			(unlocked yes)
			(layer "F.Fab")
			(hide yes)
			(effects
				(font
					(size 1.016 1.016)
					(thickness 0.1524)
				)
			)
		)
		(property "Device Type" "C1206H71"
			(at -0.127 -6.6548 270)
			(unlocked yes)
			(layer "F.Fab")
			(hide yes)
			(effects
				(font
					(size 1.016 1.016)
					(thickness 0.1524)
				)
			)
		)
		(duplicate_pad_numbers_are_jumpers no)
		(fp_line
			(start -1.016 2.2352)
			(end -1.016 0.8382)
			(stroke
				(width 0.1524)
				(type default)
			)
			(layer "F.SilkS")
		)
		(fp_line
			(start 1.016 2.2352)
			(end -1.016 2.2352)
			(stroke
				(width 0.1524)
				(type default)
			)
			(layer "F.SilkS")
		)
		(fp_line
			(start 1.016 0.8382)
			(end 1.016 2.2352)
			(stroke
				(width 0.1524)
				(type default)
			)
			(layer "F.SilkS")
		)
		(fp_line
			(start -1.016 -0.8382)
			(end -1.016 -2.2352)
			(stroke
				(width 0.1524)
				(type default)
			)
			(layer "F.SilkS")
		)
		(fp_line
			(start -1.016 -2.2352)
			(end 1.016 -2.2352)
			(stroke
				(width 0.1524)
				(type default)
			)
			(layer "F.SilkS")
		)
		(fp_line
			(start 1.016 -2.2352)
			(end 1.016 -0.8382)
			(stroke
				(width 0.1524)
				(type default)
			)
			(layer "F.SilkS")
		)
		(fp_rect
			(start -1.0922 2.3114)
			(end 1.0922 -2.3114)
			(stroke
				(width 0)
				(type default)
			)
			(fill no)
			(layer "F.CrtYd")
		)
		(fp_poly
			(pts
				(xy 1.0922 -2.3114) (xy 1.0922 2.3114) (xy -1.0922 2.3114) (xy -1.0922 -2.3114)
			)
			(stroke
				(width 0)
				(type default)
			)
			(fill no)
			(layer "F.Fab")
		)
		(pad "1" smd rect
			(at 0 -1.397 270)
			(size 1.651 1.27)
			(layers "F.Cu" "F.Mask" "F.Paste")
			(net "P5V_HDD15")
		)
		(pad "2" smd rect
			(at 0 1.397 270)
			(size 1.651 1.27)
			(layers "F.Cu" "F.Mask" "F.Paste")
			(net "GND")
		)
	)
)
